(kicad_pcb
	(version 20241229)
	(generator "pcbnew")
	(generator_version "9.0")
	(general
		(thickness 1.62)
		(legacy_teardrops no)
	)
	(paper "A3")
	(title_block
		(title "COM Express 7 Baseboard")
		(date "2025-02-04")
		(rev "1.1.2")
		(company "Antmicro Ltd")
		(comment 1 "www.antmicro.com")
		(comment 9 "footprint 690 of 802 (U40), pads 43-57 of 57")
	)
	(layers
		(0 "F.Cu" signal)
		(4 "In1.Cu" signal)
		(6 "In2.Cu" signal)
		(8 "In3.Cu" signal)
		(10 "In4.Cu" signal)
		(12 "In5.Cu" signal)
		(14 "In6.Cu" signal)
		(2 "B.Cu" signal)
		(9 "F.Adhes" user "F.Adhesive")
		(11 "B.Adhes" user "B.Adhesive")
		(13 "F.Paste" user)
		(15 "B.Paste" user)
		(5 "F.SilkS" user "F.Silkscreen")
		(7 "B.SilkS" user "B.Silkscreen")
		(1 "F.Mask" user)
		(3 "B.Mask" user)
		(17 "Dwgs.User" user "User.Drawings")
		(19 "Cmts.User" user "User.Comments")
		(21 "Eco1.User" user "User.Eco1")
		(23 "Eco2.User" user "User.Eco2")
		(25 "Edge.Cuts" user)
		(27 "Margin" user)
		(31 "F.CrtYd" user "F.Courtyard")
		(29 "B.CrtYd" user "B.Courtyard")
		(35 "F.Fab" user)
		(33 "B.Fab" user)
	)
	(footprint "antmicro-footprints:WQFN-42-1EP_3.5x9mm_P0.5mm"
		(layer "B.Cu")
		(at 193.591857 135.943686 -45)
		(descr "WQFN, 42 Pin (http://www.ti.com/lit/ds/symlink/ts3l501e.pdf#page=23), generated with kicad-footprint-generator ipc_noLead_generator.py")
		(tags "WQFN NoLead")
		(property "Reference" "U40"
			(at -0.166554 5.195942 135)
			(layer "B.SilkS")
			(effects
				(font
					(size 0.7 0.7)
					(thickness 0.15)
				)
				(justify left top mirror)
			)
		)
		(property "Value" "PI3EQX16904GL"
			(at 0 -5.819999 135)
			(layer "B.Fab")
			(effects
				(font
					(size 0.7 0.7)
					(thickness 0.15)
				)
				(justify left top mirror)
			)
		)
		(property "Datasheet" "https://www.diodes.com/part/view/PI3EQX16904GL"
			(at 0 0 135)
			(layer "B.Fab")
			(hide yes)
			(effects
				(font
					(size 1.27 1.27)
					(thickness 0.15)
				)
				(justify mirror)
			)
		)
		(property "Author" "Antmicro"
			(at 53.727 -324.573 45)
			(layer "B.Fab")
			(hide yes)
			(effects
				(font
					(size 1 1)
					(thickness 0.15)
				)
				(justify mirror)
			)
		)
		(property "License" "Apache-2.0"
			(at 53.727 -324.573 45)
			(layer "B.Fab")
			(hide yes)
			(effects
				(font
					(size 1 1)
					(thickness 0.15)
				)
				(justify mirror)
			)
		)
		(property "MPN" "PI3EQX16904GLZHEX"
			(at 53.727 -324.573 45)
			(layer "B.Fab")
			(hide yes)
			(effects
				(font
					(size 1 1)
					(thickness 0.15)
				)
				(justify mirror)
			)
		)
		(property "Manufacturer" "Diodes Incorporated"
			(at 53.727 -324.573 45)
			(layer "B.Fab")
			(hide yes)
			(effects
				(font
					(size 1 1)
					(thickness 0.15)
				)
				(justify mirror)
			)
		)
		(sheetname "PCIe redriver")
		(sheetfile "pcie_redriver.kicad_sch")
		(attr smd)
		(pad "29" smd roundrect
			(at 1.687001 -0.5 315)
			(size 0.875 0.25)
			(layers "B.Cu" "B.Mask" "B.Paste")
			(roundrect_rratio 0.25)
			(net 958 "/PCIe redriver/PCIe_{I}_C.RX1+")
			(pinfunction "A2TX+")
			(pintype "input")
			(teardrops
				(best_length_ratio 0.2)
				(max_length 1)
				(best_width_ratio 0.9)
				(max_width 2)
				(curved_edges yes)
				(filter_ratio 0.9)
				(enabled yes)
				(allow_two_segments yes)
				(prefer_zone_connections yes)
			)
		)
		(pad "30" smd roundrect
			(at 1.687 0 315)
			(size 0.875 0.25)
			(layers "B.Cu" "B.Mask" "B.Paste")
			(roundrect_rratio 0.25)
			(net 2 "+3V3")
			(pinfunction "VCC")
			(pintype "passive")
			(teardrops
				(best_length_ratio 0.2)
				(max_length 1)
				(best_width_ratio 0.9)
				(max_width 2)
				(curved_edges yes)
				(filter_ratio 0.9)
				(enabled yes)
				(allow_two_segments yes)
				(prefer_zone_connections yes)
			)
		)
		(pad "31" smd roundrect
			(at 1.687001 0.5 315)
			(size 0.875 0.25)
			(layers "B.Cu" "B.Mask" "B.Paste")
			(roundrect_rratio 0.25)
			(net 105 "/PCIe redriver/PCIe_{I}_C.RX2-")
			(pinfunction "A1TX-")
			(pintype "output")
			(teardrops
				(best_length_ratio 0.2)
				(max_length 1)
				(best_width_ratio 0.9)
				(max_width 2)
				(curved_edges yes)
				(filter_ratio 0.9)
				(enabled yes)
				(allow_two_segments yes)
				(prefer_zone_connections yes)
			)
		)
		(pad "32" smd roundrect
			(at 1.687 1 315)
			(size 0.875 0.25)
			(layers "B.Cu" "B.Mask" "B.Paste")
			(roundrect_rratio 0.25)
			(net 959 "/PCIe redriver/PCIe_{I}_C.RX2+")
			(pinfunction "A1TX+")
			(pintype "input")
			(teardrops
				(best_length_ratio 0.2)
				(max_length 1)
				(best_width_ratio 0.9)
				(max_width 2)
				(curved_edges yes)
				(filter_ratio 0.9)
				(enabled yes)
				(allow_two_segments yes)
				(prefer_zone_connections yes)
			)
		)
		(pad "33" smd roundrect
			(at 1.687 1.5 315)
			(size 0.875 0.25)
			(layers "B.Cu" "B.Mask" "B.Paste")
			(roundrect_rratio 0.25)
			(net 2 "+3V3")
			(pinfunction "VCC")
			(pintype "passive")
			(teardrops
				(best_length_ratio 0.2)
				(max_length 1)
				(best_width_ratio 0.9)
				(max_width 2)
				(curved_edges yes)
				(filter_ratio 0.9)
				(enabled yes)
				(allow_two_segments yes)
				(prefer_zone_connections yes)
			)
		)
		(pad "34" smd roundrect
			(at 1.687001 2 315)
			(size 0.875 0.25)
			(layers "B.Cu" "B.Mask" "B.Paste")
			(roundrect_rratio 0.25)
			(net 956 "/PCIe redriver/PCIe_{I}_C.RX3-")
			(pinfunction "A0TX-")
			(pintype "output")
			(teardrops
				(best_length_ratio 0.2)
				(max_length 1)
				(best_width_ratio 0.9)
				(max_width 2)
				(curved_edges yes)
				(filter_ratio 0.9)
				(enabled yes)
				(allow_two_segments yes)
				(prefer_zone_connections yes)
			)
		)
		(pad "35" smd roundrect
			(at 1.687 2.5 315)
			(size 0.875 0.25)
			(layers "B.Cu" "B.Mask" "B.Paste")
			(roundrect_rratio 0.25)
			(net 960 "/PCIe redriver/PCIe_{I}_C.RX3+")
			(pinfunction "A0TX+")
			(pintype "input")
			(teardrops
				(best_length_ratio 0.2)
				(max_length 1)
				(best_width_ratio 0.9)
				(max_width 2)
				(curved_edges yes)
				(filter_ratio 0.9)
				(enabled yes)
				(allow_two_segments yes)
				(prefer_zone_connections yes)
			)
		)
		(pad "36" smd roundrect
			(at 1.687 3 315)
			(size 0.875 0.25)
			(layers "B.Cu" "B.Mask" "B.Paste")
			(roundrect_rratio 0.25)
			(net 2 "+3V3")
			(pinfunction "VCC")
			(pintype "passive")
			(teardrops
				(best_length_ratio 0.2)
				(max_length 1)
				(best_width_ratio 0.9)
				(max_width 2)
				(curved_edges yes)
				(filter_ratio 0.9)
				(enabled yes)
				(allow_two_segments yes)
				(prefer_zone_connections yes)
			)
		)
		(pad "37" smd roundrect
			(at 1.687 3.5 315)
			(size 0.875 0.25)
			(layers "B.Cu" "B.Mask" "B.Paste")
			(roundrect_rratio 0.25)
			(net 975 "/PCIe redriver/RX_FG0")
			(pinfunction "FG0")
			(pintype "passive")
			(teardrops
				(best_length_ratio 0.2)
				(max_length 1)
				(best_width_ratio 0.9)
				(max_width 2)
				(curved_edges yes)
				(filter_ratio 0.9)
				(enabled yes)
				(allow_two_segments yes)
				(prefer_zone_connections yes)
			)
		)
		(pad "38" smd roundrect
			(at 1.687 4 315)
			(size 0.875 0.25)
			(layers "B.Cu" "B.Mask" "B.Paste")
			(roundrect_rratio 0.25)
			(net 974 "/PCIe redriver/RX_FG1")
			(pinfunction "FG1")
			(pintype "passive")
			(teardrops
				(best_length_ratio 0.2)
				(max_length 1)
				(best_width_ratio 0.9)
				(max_width 2)
				(curved_edges yes)
				(filter_ratio 0.9)
				(enabled yes)
				(allow_two_segments yes)
				(prefer_zone_connections yes)
			)
		)
		(pad "39" smd roundrect
			(at 0.75 4.438 315)
			(size 0.25 0.875)
			(layers "B.Cu" "B.Mask" "B.Paste")
			(roundrect_rratio 0.25)
			(net 978 "/PCIe redriver/RX_EQ0")
			(pinfunction "EQ0")
			(pintype "passive")
			(teardrops
				(best_length_ratio 0.2)
				(max_length 1)
				(best_width_ratio 0.9)
				(max_width 2)
				(curved_edges yes)
				(filter_ratio 0.9)
				(enabled yes)
				(allow_two_segments yes)
				(prefer_zone_connections yes)
			)
		)
		(pad "40" smd roundrect
			(at 0.25 4.438 315)
			(size 0.25 0.875)
			(layers "B.Cu" "B.Mask" "B.Paste")
			(roundrect_rratio 0.25)
			(net 977 "/PCIe redriver/RX_EQ1")
			(pinfunction "EQ1")
			(pintype "passive")
			(teardrops
				(best_length_ratio 0.2)
				(max_length 1)
				(best_width_ratio 0.9)
				(max_width 2)
				(curved_edges yes)
				(filter_ratio 0.9)
				(enabled yes)
				(allow_two_segments yes)
				(prefer_zone_connections yes)
			)
		)
		(pad "41" smd roundrect
			(at -0.25 4.438 315)
			(size 0.25 0.875)
			(layers "B.Cu" "B.Mask" "B.Paste")
			(roundrect_rratio 0.25)
			(net 1 "GND")
			(pinfunction "AD2")
			(pintype "passive")
			(teardrops
				(best_length_ratio 0.2)
				(max_length 1)
				(best_width_ratio 0.9)
				(max_width 2)
				(curved_edges yes)
				(filter_ratio 0.9)
				(enabled yes)
				(allow_two_segments yes)
				(prefer_zone_connections yes)
			)
		)
		(pad "42" smd roundrect
			(at -0.75 4.438 315)
			(size 0.25 0.875)
			(layers "B.Cu" "B.Mask" "B.Paste")
			(roundrect_rratio 0.25)
			(net 1 "GND")
			(pinfunction "AD3")
			(pintype "passive")
			(teardrops
				(best_length_ratio 0.2)
				(max_length 1)
				(best_width_ratio 0.9)
				(max_width 2)
				(curved_edges yes)
				(filter_ratio 0.9)
				(enabled yes)
				(allow_two_segments yes)
				(prefer_zone_connections yes)
			)
		)
		(pad "43" smd rect
			(at 0 0 315)
			(size 2.05 7.55)
			(layers "B.Cu" "B.Mask")
			(net 1 "GND")
			(pinfunction "GND")
			(pintype "power_in")
			(teardrops
				(best_length_ratio 0.2)
				(max_length 1)
				(best_width_ratio 0.9)
				(max_width 2)
				(curved_edges yes)
				(filter_ratio 0.9)
				(enabled no)
				(allow_two_segments yes)
				(prefer_zone_connections yes)
			)
		)
	)
)
